# T6G (Grand Teton) — schematic netlist excerpt (pin names and nets, part order shuffled) for the footprints in the layout excerpt that follows; sources: Cadence DE-HDL packaged netlist, KiCad conversion of 04192023_DAF0TMB3IC0_F0TG_MB_C_brd_V02_OCP.brd

U244  NC7SB3157  NC7SB3157P6X EMPTY  pkg SMLF  page 143
  B1  = OCP_SFF_NOT_PRSNT_RBT_ARB_IN
  GND  = GND
  B0  = OCP_SFF_RBT_ARB_IN
  A  = OCP_SFF_RBT_ARB_IN_MUX1_R
  VCC  = P3V3_AUX
  S  = OCP_SFF_PRSNT_ALL_R3_N

(kicad_pcb
	(version 20260206)
	(generator "pcbnew")
	(generator_version "10.0")
	(general
		(thickness 1.6)
		(legacy_teardrops no)
	)
	(paper "A4")
	(title_block
		(title "04192023_DAF0TMB3IC0_F0TG_MB_C_brd_V02_OCP.brd")
		(comment 1 "Grand Teton / footprints 3115-3115 of 8354")
	)
	(layers
		(0 "F.Cu" signal "TOP")
		(4 "In1.Cu" signal "GND")
		(6 "In2.Cu" signal "IN1")
		(8 "In3.Cu" signal "GND1")
		(10 "In4.Cu" signal "IN2")
		(12 "In5.Cu" signal "GND2")
		(14 "In6.Cu" signal "IN3")
		(16 "In7.Cu" signal "GND3")
		(18 "In8.Cu" signal "VCC")
		(20 "In9.Cu" signal "VCC1")
		(22 "In10.Cu" signal "GND4")
		(24 "In11.Cu" signal "IN4")
		(26 "In12.Cu" signal "GND5")
		(28 "In13.Cu" signal "IN5")
		(30 "In14.Cu" signal "GND6")
		(32 "In15.Cu" signal "IN6")
		(34 "In16.Cu" signal "GND7")
		(2 "B.Cu" signal "BOTTOM")
		(9 "F.Adhes" user "F.Adhesive")
		(11 "B.Adhes" user "B.Adhesive")
		(13 "F.Paste" user "Package Geometry/Pastemask Top")
		(15 "B.Paste" user "Package Geometry/Pastemask Bottom")
		(5 "F.SilkS" user "Ref Des/Silkscreen Top")
		(7 "B.SilkS" user "Ref Des/Silkscreen Bottom")
		(1 "F.Mask" user "Board Geometry/Soldermask Top")
		(3 "B.Mask" user "Board Geometry/Soldermask Bottom")
		(17 "Dwgs.User" user "User.Drawings")
		(19 "Cmts.User" user "User.Comments")
		(21 "Eco1.User" user "User.Eco1")
		(23 "Eco2.User" user "User.Eco2")
		(25 "Edge.Cuts" user "Board Geometry/Outline")
		(27 "Margin" user)
		(31 "F.CrtYd" user "Package Geometry/Place Bound Top")
		(29 "B.CrtYd" user "Package Geometry/Place Bound Bottom")
		(35 "F.Fab" user "Ref Des/Assembly Top")
		(33 "B.Fab" user "Ref Des/Assembly Bottom")
	)
	(footprint ""
		(layer "F.Cu")
		(at 153.88463 -95.612458)
		(property "Reference" "U244"
			(at 0.0762 1.95961 0)
			(unlocked yes)
			(layer "F.SilkS")
			(effects
				(font
					(size 0.7874 0.5842)
					(thickness 0.1524)
				)
			)
		)
		(property "Value" ""
			(at 0 0 0)
			(layer "F.Fab")
			(effects
				(font
					(size 1.27 1.27)
				)
			)
		)
		(duplicate_pad_numbers_are_jumpers no)
		(fp_line
			(start -1.7272 1.1176)
			(end -1.7272 -1.1176)
			(stroke
				(width 0.1524)
				(type default)
			)
			(layer "F.SilkS")
		)
		(fp_line
			(start -0.254 -1.1176)
			(end -1.7272 -1.1176)
			(stroke
				(width 0.1524)
				(type default)
			)
			(layer "F.SilkS")
		)
		(fp_line
			(start 0 -0.7366)
			(end -0.254 -1.1176)
			(stroke
				(width 0.1524)
				(type default)
			)
			(layer "F.SilkS")
		)
		(fp_line
			(start 0.254 -1.1176)
			(end 0 -0.7366)
			(stroke
				(width 0.1524)
				(type default)
			)
			(layer "F.SilkS")
		)
		(fp_line
			(start 1.7272 -1.1176)
			(end 0.254 -1.1176)
			(stroke
				(width 0.1524)
				(type default)
			)
			(layer "F.SilkS")
		)
		(fp_line
			(start 1.7272 -1.1176)
			(end 1.7272 1.1176)
			(stroke
				(width 0.1524)
				(type default)
			)
			(layer "F.SilkS")
		)
		(fp_line
			(start 1.7272 1.1176)
			(end -1.7272 1.1176)
			(stroke
				(width 0.1524)
				(type default)
			)
			(layer "F.SilkS")
		)
		(fp_poly
			(pts
				(xy -2.7178 -1.030986) (xy -1.9558 -0.649986) (xy -2.7178 -0.268986)
			)
			(stroke
				(width 0)
				(type default)
			)
			(fill yes)
			(layer "F.SilkS")
		)
		(fp_line
			(start -1.5748 -1.1176)
			(end -1.5748 1.1176)
			(stroke
				(width 0.1)
				(type default)
			)
			(layer "F.Fab")
		)
		(fp_line
			(start -1.5748 1.1176)
			(end 1.5748 1.1176)
			(stroke
				(width 0.1)
				(type default)
			)
			(layer "F.Fab")
		)
		(fp_line
			(start 1.5748 -1.1176)
			(end -1.5748 -1.1176)
			(stroke
				(width 0.1)
				(type default)
			)
			(layer "F.Fab")
		)
		(fp_line
			(start 1.5748 1.1176)
			(end 1.5748 -1.1176)
			(stroke
				(width 0.1)
				(type default)
			)
			(layer "F.Fab")
		)
		(fp_poly
			(pts
				(xy -1.9558 -0.649986) (xy -2.7178 -0.268986) (xy -2.7178 -1.030986)
			)
			(stroke
				(width 0)
				(type default)
			)
			(fill yes)
			(layer "F.Fab")
		)
		(pad "1" smd rect
			(at -0.999998 -0.649986 270)
			(size 0.3556 1.1176)
			(layers "F.Cu" "F.Mask" "F.Paste")
			(net "OCP_SFF_NOT_PRSNT_RBT_ARB_IN")
		)
		(pad "2" smd rect
			(at -0.999998 0 270)
			(size 0.3556 1.1176)
			(layers "F.Cu" "F.Mask" "F.Paste")
			(net "GND")
		)
		(pad "3" smd rect
			(at -0.999998 0.649986 270)
			(size 0.3556 1.1176)
			(layers "F.Cu" "F.Mask" "F.Paste")
			(net "OCP_SFF_RBT_ARB_IN")
		)
		(pad "4" smd rect
			(at 0.999998 0.649986 270)
			(size 0.3556 1.1176)
			(layers "F.Cu" "F.Mask" "F.Paste")
			(net "OCP_SFF_RBT_ARB_IN_MUX1_R")
		)
		(pad "5" smd rect
			(at 0.999998 0 270)
			(size 0.3556 1.1176)
			(layers "F.Cu" "F.Mask" "F.Paste")
			(net "P3V3_AUX")
		)
		(pad "6" smd rect
			(at 0.999998 -0.649986 270)
			(size 0.3556 1.1176)
			(layers "F.Cu" "F.Mask" "F.Paste")
			(net "OCP_SFF_PRSNT_ALL_R3_N")
		)
	)
)
